(kicad_pcb
	(version 20260206)
	(generator "pcbnew")
	(generator_version "10.0")
	(general
		(thickness 1.6)
		(legacy_teardrops no)
	)
	(paper "A4")
	(title_block
		(title "timecard-production-celestica-r4006 — R4006-B0001-02_R01.brd")
		(comment 1 "Time Appliance Project (Time Card) / footprints 772-777 of 1113")
	)
	(layers
		(0 "F.Cu" signal "TOP")
		(4 "In1.Cu" signal "L02_GND1")
		(6 "In2.Cu" signal "L03_SIG1")
		(8 "In3.Cu" signal "L04_GND2")
		(10 "In4.Cu" signal "L05_VCC1")
		(12 "In5.Cu" signal "L06_VCC2")
		(14 "In6.Cu" signal "L07_GND3")
		(16 "In7.Cu" signal "L08_SIG2")
		(18 "In8.Cu" signal "L09_GND4")
		(2 "B.Cu" signal "BOTTOM")
		(9 "F.Adhes" user "F.Adhesive")
		(11 "B.Adhes" user "B.Adhesive")
		(13 "F.Paste" user "Package Geometry/Pastemask Top")
		(15 "B.Paste" user "Package Geometry/Pastemask Bottom")
		(5 "F.SilkS" user "Ref Des/Silkscreen Top")
		(7 "B.SilkS" user "Ref Des/Silkscreen Bottom")
		(1 "F.Mask" user "Board Geometry/Soldermask Top")
		(3 "B.Mask" user "Board Geometry/Soldermask Bottom")
		(17 "Dwgs.User" user "User.Drawings")
		(19 "Cmts.User" user "User.Comments")
		(21 "Eco1.User" user "User.Eco1")
		(23 "Eco2.User" user "User.Eco2")
		(25 "Edge.Cuts" user "Board Geometry/Outline")
		(27 "Margin" user)
		(31 "F.CrtYd" user "Package Geometry/Place Bound Top")
		(29 "B.CrtYd" user "Package Geometry/Place Bound Bottom")
		(35 "F.Fab" user "Ref Des/Assembly Top")
		(33 "B.Fab" user "Ref Des/Assembly Bottom")
	)
	(footprint ""
		(layer "B.Cu")
		(at 93.0148 -75.819 90)
		(property "Reference" "C180"
			(at 0.508 1.56083 270)
			(unlocked yes)
			(layer "B.SilkS")
			(effects
				(font
					(size 0.7874 0.5842)
					(thickness 0.1524)
				)
				(justify mirror)
			)
		)
		(property "Value" "VAL*"
			(at -0.0762 3.134106 90)
			(unlocked yes)
			(layer "B.Fab")
			(hide yes)
			(effects
				(font
					(size 0.7874 0.5842)
					(thickness 0.1524)
				)
				(justify mirror)
			)
		)
		(property "Tolerance" "TOL*"
			(at -0.0762 4.048506 90)
			(unlocked yes)
			(layer "Cmts.User")
			(hide yes)
			(effects
				(font
					(size 0.7874 0.5842)
					(thickness 0.1524)
				)
				(justify mirror)
			)
		)
		(property "User Part Number" "PARTNUM*"
			(at -0.1016 5.013706 90)
			(unlocked yes)
			(layer "Cmts.User")
			(hide yes)
			(effects
				(font
					(size 0.7874 0.5842)
					(thickness 0.1524)
				)
				(justify mirror)
			)
		)
		(property "Device Type" "CAPACITOR-G107-0F226-CM,22UF,2A"
			(at -0.0508 2.194306 90)
			(unlocked yes)
			(layer "B.Fab")
			(hide yes)
			(effects
				(font
					(size 0.7874 0.5842)
					(thickness 0.1524)
				)
				(justify mirror)
			)
		)
		(duplicate_pad_numbers_are_jumpers no)
		(fp_line
			(start 1.5748 -0.9398)
			(end 1.5748 0.9398)
			(stroke
				(width 0.1)
				(type default)
			)
			(layer "B.SilkS")
		)
		(fp_line
			(start -1.5748 -0.9398)
			(end 1.5748 -0.9398)
			(stroke
				(width 0.1)
				(type default)
			)
			(layer "B.SilkS")
		)
		(fp_line
			(start 1.5748 0.9398)
			(end -1.5748 0.9398)
			(stroke
				(width 0.1)
				(type default)
			)
			(layer "B.SilkS")
		)
		(fp_line
			(start -1.5748 0.9398)
			(end -1.5748 -0.9398)
			(stroke
				(width 0.1)
				(type default)
			)
			(layer "B.SilkS")
		)
		(fp_rect
			(start 1.5748 -0.9398)
			(end -1.5748 0.9398)
			(stroke
				(width 0)
				(type default)
			)
			(fill no)
			(layer "B.CrtYd")
		)
		(fp_line
			(start 1.016 -0.635)
			(end 1.016 0.635)
			(stroke
				(width 0.1)
				(type default)
			)
			(layer "B.Fab")
		)
		(fp_line
			(start -1.016 -0.635)
			(end 1.016 -0.635)
			(stroke
				(width 0.1)
				(type default)
			)
			(layer "B.Fab")
		)
		(fp_line
			(start 1.016 0.635)
			(end -1.016 0.635)
			(stroke
				(width 0.1)
				(type default)
			)
			(layer "B.Fab")
		)
		(fp_line
			(start -1.016 0.635)
			(end -1.016 -0.635)
			(stroke
				(width 0.1)
				(type default)
			)
			(layer "B.Fab")
		)
		(pad "1" smd rect
			(at 0.8382 0 270)
			(size 0.9652 1.3716)
			(layers "B.Cu" "B.Mask" "B.Paste")
			(net "XP3R3V")
		)
		(pad "2" smd rect
			(at -0.8382 0 270)
			(size 0.9652 1.3716)
			(layers "B.Cu" "B.Mask" "B.Paste")
			(net "SG")
		)
		(zone
			(layer "B.Cu")
			(hatch none 0.5)
			(connect_pads
				(clearance 0)
			)
			(min_thickness 0.25)
			(keepout
				(tracks allowed)
				(vias not_allowed)
				(pads allowed)
				(copperpour not_allowed)
				(footprints allowed)
			)
			(placement
				(enabled no)
				(sheetname "")
			)
			(fill
				(thermal_gap 0.5)
				(thermal_bridge_width 0.5)
				(island_removal_mode 0)
			)
			(polygon
				(pts
					(xy 92.3798 -76.0476) (xy 92.3798 -75.5904) (xy 93.6498 -75.5904) (xy 93.6498 -76.0476)
				)
			)
		)
	)
	(footprint ""
		(layer "B.Cu")
		(at 59.51474 -15.36446 -90)
		(property "Reference" "C19"
			(at -2.41554 0.11811 270)
			(unlocked yes)
			(layer "B.SilkS")
			(effects
				(font
					(size 0.7874 0.5842)
					(thickness 0.1524)
				)
				(justify mirror)
			)
		)
		(property "Value" "VAL*"
			(at -0.0762 2.067306 270)
			(unlocked yes)
			(layer "B.Fab")
			(hide yes)
			(effects
				(font
					(size 0.7874 0.5842)
					(thickness 0.1524)
				)
				(justify mirror)
			)
		)
		(property "Tolerance" "TOL*"
			(at -0.0762 3.032506 270)
			(unlocked yes)
			(layer "Cmts.User")
			(hide yes)
			(effects
				(font
					(size 0.7874 0.5842)
					(thickness 0.1524)
				)
				(justify mirror)
			)
		)
		(property "User Part Number" "PARTNUM*"
			(at -0.1016 4.023106 270)
			(unlocked yes)
			(layer "Cmts.User")
			(hide yes)
			(effects
				(font
					(size 0.7874 0.5842)
					(thickness 0.1524)
				)
				(justify mirror)
			)
		)
		(property "Device Type" "CAPACITOR-G105-0B104-CK,0.1UF,A"
			(at -0.0508 1.127506 270)
			(unlocked yes)
			(layer "B.Fab")
			(hide yes)
			(effects
				(font
					(size 0.7874 0.5842)
					(thickness 0.1524)
				)
				(justify mirror)
			)
		)
		(duplicate_pad_numbers_are_jumpers no)
		(fp_line
			(start -1.143 0.5588)
			(end -1.143 -0.5588)
			(stroke
				(width 0.1)
				(type default)
			)
			(layer "B.SilkS")
		)
		(fp_line
			(start 1.143 0.5588)
			(end -1.143 0.5588)
			(stroke
				(width 0.1)
				(type default)
			)
			(layer "B.SilkS")
		)
		(fp_line
			(start -1.143 -0.5588)
			(end 1.143 -0.5588)
			(stroke
				(width 0.1)
				(type default)
			)
			(layer "B.SilkS")
		)
		(fp_line
			(start 1.143 -0.5588)
			(end 1.143 0.5588)
			(stroke
				(width 0.1)
				(type default)
			)
			(layer "B.SilkS")
		)
		(fp_rect
			(start 1.143 0.5588)
			(end -1.143 -0.5588)
			(stroke
				(width 0)
				(type default)
			)
			(fill no)
			(layer "B.CrtYd")
		)
		(fp_line
			(start -0.508 0.3048)
			(end -0.508 -0.3048)
			(stroke
				(width 0.1)
				(type default)
			)
			(layer "B.Fab")
		)
		(fp_line
			(start 0.508 0.3048)
			(end -0.508 0.3048)
			(stroke
				(width 0.1)
				(type default)
			)
			(layer "B.Fab")
		)
		(fp_line
			(start -0.508 -0.3048)
			(end 0.508 -0.3048)
			(stroke
				(width 0.1)
				(type default)
			)
			(layer "B.Fab")
		)
		(fp_line
			(start 0.508 -0.3048)
			(end 0.508 0.3048)
			(stroke
				(width 0.1)
				(type default)
			)
			(layer "B.Fab")
		)
		(pad "1" smd rect
			(at 0.5334 0 90)
			(size 0.7112 0.6096)
			(layers "B.Cu" "B.Mask" "B.Paste")
			(net "C_PCIEREFCLKP")
		)
		(pad "2" smd rect
			(at -0.5334 0 90)
			(size 0.7112 0.6096)
			(layers "B.Cu" "B.Mask" "B.Paste")
			(net "PCIE_REFCLKP")
		)
		(zone
			(layer "B.Cu")
			(hatch none 0.5)
			(connect_pads
				(clearance 0)
			)
			(min_thickness 0.25)
			(keepout
				(tracks allowed)
				(vias not_allowed)
				(pads allowed)
				(copperpour not_allowed)
				(footprints allowed)
			)
			(placement
				(enabled no)
				(sheetname "")
			)
			(fill
				(thermal_gap 0.5)
				(thermal_bridge_width 0.5)
				(island_removal_mode 0)
			)
			(polygon
				(pts
					(xy 59.20994 -15.28826) (xy 59.81954 -15.28826) (xy 59.81954 -15.44066) (xy 59.20994 -15.44066)
				)
			)
		)
	)
	(footprint ""
		(layer "B.Cu")
		(at 105.347008 -38.823138)
		(property "Reference" "C204"
			(at -41.656508 1.377188 0)
			(unlocked yes)
			(layer "B.SilkS")
			(effects
				(font
					(size 0.635 0.4064)
					(thickness 0.1524)
				)
				(justify mirror)
			)
		)
		(property "Value" "VAL*"
			(at 0 3.718306 0)
			(unlocked yes)
			(layer "B.Fab")
			(hide yes)
			(effects
				(font
					(size 0.7874 0.5842)
					(thickness 0.127)
				)
				(justify mirror)
			)
		)
		(property "Device Type" "CAPACITOR-G105-0B104-CK,0.1UF,A"
			(at 0 1.432306 0)
			(unlocked yes)
			(layer "B.Fab")
			(hide yes)
			(effects
				(font
					(size 0.7874 0.5842)
					(thickness 0.127)
				)
				(justify mirror)
			)
		)
		(property "User Part Number" "PARTNUM*"
			(at 0 2.575306 0)
			(unlocked yes)
			(layer "Cmts.User")
			(hide yes)
			(effects
				(font
					(size 0.7874 0.5842)
					(thickness 0.127)
				)
				(justify mirror)
			)
		)
		(property "Tolerance" "TOL*"
			(at 0 4.861306 0)
			(unlocked yes)
			(layer "Cmts.User")
			(hide yes)
			(effects
				(font
					(size 0.7874 0.5842)
					(thickness 0.127)
				)
				(justify mirror)
			)
		)
		(duplicate_pad_numbers_are_jumpers no)
		(fp_line
			(start -0.970026 -0.4699)
			(end -0.970026 0.4699)
			(stroke
				(width 0.1)
				(type default)
			)
			(layer "B.SilkS")
		)
		(fp_line
			(start -0.970026 0.4699)
			(end 0.970026 0.4699)
			(stroke
				(width 0.1)
				(type default)
			)
			(layer "B.SilkS")
		)
		(fp_line
			(start 0.970026 -0.4699)
			(end -0.970026 -0.4699)
			(stroke
				(width 0.1)
				(type default)
			)
			(layer "B.SilkS")
		)
		(fp_line
			(start 0.970026 0.4699)
			(end 0.970026 -0.4699)
			(stroke
				(width 0.1)
				(type default)
			)
			(layer "B.SilkS")
		)
		(fp_poly
			(pts
				(xy 0.970026 0.4699) (xy -0.970026 0.4699) (xy -0.970026 -0.4699) (xy 0.970026 -0.4699)
			)
			(stroke
				(width 0)
				(type default)
			)
			(fill no)
			(layer "B.CrtYd")
		)
		(fp_line
			(start -0.508 -0.3048)
			(end -0.508 0.3048)
			(stroke
				(width 0.1)
				(type default)
			)
			(layer "B.Fab")
		)
		(fp_line
			(start -0.508 0.3048)
			(end 0.508 0.3048)
			(stroke
				(width 0.1)
				(type default)
			)
			(layer "B.Fab")
		)
		(fp_line
			(start 0.508 -0.3048)
			(end -0.508 -0.3048)
			(stroke
				(width 0.1)
				(type default)
			)
			(layer "B.Fab")
		)
		(fp_line
			(start 0.508 0.3048)
			(end 0.508 -0.3048)
			(stroke
				(width 0.1)
				(type default)
			)
			(layer "B.Fab")
		)
		(pad "1" smd circle
			(at 0.500126 0 180)
			(size 0.635 0.635)
			(layers "B.Cu" "B.Mask" "B.Paste")
			(net "XP2R5V_FPGA")
		)
		(pad "2" smd circle
			(at -0.500126 0 180)
			(size 0.635 0.635)
			(layers "B.Cu" "B.Mask" "B.Paste")
			(net "SG")
		)
	)
	(footprint ""
		(layer "B.Cu")
		(at 99.346766 -37.82314)
		(property "Reference" "C110"
			(at -42.196766 2.16789 0)
			(unlocked yes)
			(layer "B.SilkS")
			(effects
				(font
					(size 0.635 0.4064)
					(thickness 0.1524)
				)
				(justify mirror)
			)
		)
		(property "Value" "VAL*"
			(at 0 3.718306 0)
			(unlocked yes)
			(layer "B.Fab")
			(hide yes)
			(effects
				(font
					(size 0.7874 0.5842)
					(thickness 0.127)
				)
				(justify mirror)
			)
		)
		(property "Tolerance" "TOL*"
			(at 0 4.861306 0)
			(unlocked yes)
			(layer "Cmts.User")
			(hide yes)
			(effects
				(font
					(size 0.7874 0.5842)
					(thickness 0.127)
				)
				(justify mirror)
			)
		)
		(property "User Part Number" "PARTNUM*"
			(at 0 2.575306 0)
			(unlocked yes)
			(layer "Cmts.User")
			(hide yes)
			(effects
				(font
					(size 0.7874 0.5842)
					(thickness 0.127)
				)
				(justify mirror)
			)
		)
		(property "Device Type" "CAPACITOR-G105-0B104-CK,0.1UF,A"
			(at 0 1.432306 0)
			(unlocked yes)
			(layer "B.Fab")
			(hide yes)
			(effects
				(font
					(size 0.7874 0.5842)
					(thickness 0.127)
				)
				(justify mirror)
			)
		)
		(duplicate_pad_numbers_are_jumpers no)
		(fp_line
			(start -0.970026 -0.4699)
			(end -0.970026 0.4699)
			(stroke
				(width 0.1)
				(type default)
			)
			(layer "B.SilkS")
		)
		(fp_line
			(start -0.970026 0.4699)
			(end 0.970026 0.4699)
			(stroke
				(width 0.1)
				(type default)
			)
			(layer "B.SilkS")
		)
		(fp_line
			(start 0.970026 -0.4699)
			(end -0.970026 -0.4699)
			(stroke
				(width 0.1)
				(type default)
			)
			(layer "B.SilkS")
		)
		(fp_line
			(start 0.970026 0.4699)
			(end 0.970026 -0.4699)
			(stroke
				(width 0.1)
				(type default)
			)
			(layer "B.SilkS")
		)
		(fp_poly
			(pts
				(xy 0.970026 0.4699) (xy -0.970026 0.4699) (xy -0.970026 -0.4699) (xy 0.970026 -0.4699)
			)
			(stroke
				(width 0)
				(type default)
			)
			(fill no)
			(layer "B.CrtYd")
		)
		(fp_line
			(start -0.508 -0.3048)
			(end -0.508 0.3048)
			(stroke
				(width 0.1)
				(type default)
			)
			(layer "B.Fab")
		)
		(fp_line
			(start -0.508 0.3048)
			(end 0.508 0.3048)
			(stroke
				(width 0.1)
				(type default)
			)
			(layer "B.Fab")
		)
		(fp_line
			(start 0.508 -0.3048)
			(end -0.508 -0.3048)
			(stroke
				(width 0.1)
				(type default)
			)
			(layer "B.Fab")
		)
		(fp_line
			(start 0.508 0.3048)
			(end 0.508 -0.3048)
			(stroke
				(width 0.1)
				(type default)
			)
			(layer "B.Fab")
		)
		(pad "1" smd circle
			(at 0.500126 0 180)
			(size 0.635 0.635)
			(layers "B.Cu" "B.Mask" "B.Paste")
			(net "FPGA_MGTAVTT")
		)
		(pad "2" smd circle
			(at -0.500126 0 180)
			(size 0.635 0.635)
			(layers "B.Cu" "B.Mask" "B.Paste")
			(net "SG")
		)
	)
	(footprint ""
		(layer "B.Cu")
		(at 21.7932 -71.374 -90)
		(property "Reference" "R343"
			(at -0.254 1.13157 270)
			(unlocked yes)
			(layer "B.SilkS")
			(effects
				(font
					(size 0.7874 0.5842)
					(thickness 0.1524)
				)
				(justify mirror)
			)
		)
		(property "Value" "VAL*"
			(at -0.02032 2.13233 270)
			(unlocked yes)
			(layer "B.Fab")
			(hide yes)
			(effects
				(font
					(size 0.7874 0.5842)
					(thickness 0.1524)
				)
				(justify mirror)
			)
		)
		(property "Tolerance" "TOL*"
			(at -0.044704 3.05435 270)
			(unlocked yes)
			(layer "Cmts.User")
			(hide yes)
			(effects
				(font
					(size 0.7874 0.5842)
					(thickness 0.1524)
				)
				(justify mirror)
			)
		)
		(property "User Part Number" "PARTNUM*"
			(at -0.02032 4.024884 270)
			(unlocked yes)
			(layer "Cmts.User")
			(hide yes)
			(effects
				(font
					(size 0.7874 0.5842)
					(thickness 0.1524)
				)
				(justify mirror)
			)
		)
		(property "Device Type" "RESISTOR-G155-100R0-J0,0OHM,-"
			(at -0.008382 1.210564 270)
			(unlocked yes)
			(layer "B.Fab")
			(hide yes)
			(effects
				(font
					(size 0.7874 0.5842)
					(thickness 0.1524)
				)
				(justify mirror)
			)
		)
		(duplicate_pad_numbers_are_jumpers no)
		(fp_line
			(start -1.143 0.5588)
			(end -1.143 -0.5588)
			(stroke
				(width 0.1)
				(type default)
			)
			(layer "B.SilkS")
		)
		(fp_line
			(start 1.143 0.5588)
			(end -1.143 0.5588)
			(stroke
				(width 0.1)
				(type default)
			)
			(layer "B.SilkS")
		)
		(fp_line
			(start -1.143 -0.5588)
			(end 1.143 -0.5588)
			(stroke
				(width 0.1)
				(type default)
			)
			(layer "B.SilkS")
		)
		(fp_line
			(start 1.143 -0.5588)
			(end 1.143 0.5588)
			(stroke
				(width 0.1)
				(type default)
			)
			(layer "B.SilkS")
		)
		(fp_poly
			(pts
				(xy 1.143 0.5588) (xy -1.143 0.5588) (xy -1.143 -0.5588) (xy 1.143 -0.5588)
			)
			(stroke
				(width 0)
				(type default)
			)
			(fill no)
			(layer "B.CrtYd")
		)
		(fp_line
			(start -0.508 0.3048)
			(end -0.508 -0.3048)
			(stroke
				(width 0.1)
				(type default)
			)
			(layer "B.Fab")
		)
		(fp_line
			(start 0.508 0.3048)
			(end -0.508 0.3048)
			(stroke
				(width 0.1)
				(type default)
			)
			(layer "B.Fab")
		)
		(fp_line
			(start -0.508 -0.3048)
			(end 0.508 -0.3048)
			(stroke
				(width 0.1)
				(type default)
			)
			(layer "B.Fab")
		)
		(fp_line
			(start 0.508 -0.3048)
			(end 0.508 0.3048)
			(stroke
				(width 0.1)
				(type default)
			)
			(layer "B.Fab")
		)
		(pad "1" smd rect
			(at 0.5334 0 90)
			(size 0.7112 0.6096)
			(layers "B.Cu" "B.Mask" "B.Paste")
			(net "UNNAMED_8_ICP10100LGA10_I24_RES")
		)
		(pad "2" smd rect
			(at -0.5334 0 90)
			(size 0.7112 0.6096)
			(layers "B.Cu" "B.Mask" "B.Paste")
			(net "SG")
		)
		(zone
			(layer "B.Cu")
			(hatch none 0.5)
			(connect_pads
				(clearance 0)
			)
			(min_thickness 0.25)
			(keepout
				(tracks not_allowed)
				(vias allowed)
				(pads allowed)
				(copperpour not_allowed)
				(footprints allowed)
			)
			(placement
				(enabled no)
				(sheetname "")
			)
			(fill
				(thermal_gap 0.5)
				(thermal_bridge_width 0.5)
				(island_removal_mode 0)
			)
			(polygon
				(pts
					(xy 21.4884 -71.2978) (xy 22.098 -71.2978) (xy 22.098 -71.4502) (xy 21.4884 -71.4502)
				)
			)
		)
		(zone
			(layer "B.Cu")
			(hatch none 0.5)
			(connect_pads
				(clearance 0)
			)
			(min_thickness 0.25)
			(keepout
				(tracks allowed)
				(vias not_allowed)
				(pads allowed)
				(copperpour not_allowed)
				(footprints allowed)
			)
			(placement
				(enabled no)
				(sheetname "")
			)
			(fill
				(thermal_gap 0.5)
				(thermal_bridge_width 0.5)
				(island_removal_mode 0)
			)
			(polygon
				(pts
					(xy 21.4884 -71.2978) (xy 22.098 -71.2978) (xy 22.098 -71.4502) (xy 21.4884 -71.4502)
				)
			)
		)
	)
	(footprint ""
		(layer "B.Cu")
		(at 140.97 -104.521 180)
		(property "Reference" "R108"
			(at 0.889 -3.84937 0)
			(unlocked yes)
			(layer "B.SilkS")
			(effects
				(font
					(size 0.7874 0.5842)
					(thickness 0.1524)
				)
				(justify mirror)
			)
		)
		(property "Value" "VAL*"
			(at -0.02032 2.13233 180)
			(unlocked yes)
			(layer "B.Fab")
			(hide yes)
			(effects
				(font
					(size 0.7874 0.5842)
					(thickness 0.1524)
				)
				(justify mirror)
			)
		)
		(property "Tolerance" "TOL*"
			(at -0.044704 3.05435 180)
			(unlocked yes)
			(layer "Cmts.User")
			(hide yes)
			(effects
				(font
					(size 0.7874 0.5842)
					(thickness 0.1524)
				)
				(justify mirror)
			)
		)
		(property "User Part Number" "PARTNUM*"
			(at -0.02032 4.024884 180)
			(unlocked yes)
			(layer "Cmts.User")
			(hide yes)
			(effects
				(font
					(size 0.7874 0.5842)
					(thickness 0.1524)
				)
				(justify mirror)
			)
		)
		(property "Device Type" "RESISTOR-G155-11000-01,100OHM,A"
			(at -0.008382 1.210564 180)
			(unlocked yes)
			(layer "B.Fab")
			(hide yes)
			(effects
				(font
					(size 0.7874 0.5842)
					(thickness 0.1524)
				)
				(justify mirror)
			)
		)
		(duplicate_pad_numbers_are_jumpers no)
		(fp_line
			(start 1.143 0.5588)
			(end -1.143 0.5588)
			(stroke
				(width 0.1)
				(type default)
			)
			(layer "B.SilkS")
		)
		(fp_line
			(start 1.143 -0.5588)
			(end 1.143 0.5588)
			(stroke
				(width 0.1)
				(type default)
			)
			(layer "B.SilkS")
		)
		(fp_line
			(start -1.143 0.5588)
			(end -1.143 -0.5588)
			(stroke
				(width 0.1)
				(type default)
			)
			(layer "B.SilkS")
		)
		(fp_line
			(start -1.143 -0.5588)
			(end 1.143 -0.5588)
			(stroke
				(width 0.1)
				(type default)
			)
			(layer "B.SilkS")
		)
		(fp_rect
			(start 1.143 0.5588)
			(end -1.143 -0.5588)
			(stroke
				(width 0)
				(type default)
			)
			(fill no)
			(layer "B.CrtYd")
		)
		(fp_line
			(start 0.508 0.3048)
			(end -0.508 0.3048)
			(stroke
				(width 0.1)
				(type default)
			)
			(layer "B.Fab")
		)
		(fp_line
			(start 0.508 -0.3048)
			(end 0.508 0.3048)
			(stroke
				(width 0.1)
				(type default)
			)
			(layer "B.Fab")
		)
		(fp_line
			(start -0.508 0.3048)
			(end -0.508 -0.3048)
			(stroke
				(width 0.1)
				(type default)
			)
			(layer "B.Fab")
		)
		(fp_line
			(start -0.508 -0.3048)
			(end 0.508 -0.3048)
			(stroke
				(width 0.1)
				(type default)
			)
			(layer "B.Fab")
		)
		(pad "1" smd rect
			(at 0.5334 0)
			(size 0.7112 0.6096)
			(layers "B.Cu" "B.Mask" "B.Paste")
			(net "UNNAMED_14_OPTICAL_I141_A")
		)
		(pad "2" smd rect
			(at -0.5334 0)
			(size 0.7112 0.6096)
			(layers "B.Cu" "B.Mask" "B.Paste")
			(net "UNNAMED_14_RESISTOR_I58_2")
		)
		(zone
			(layer "B.Cu")
			(hatch none 0.5)
			(connect_pads
				(clearance 0)
			)
			(min_thickness 0.25)
			(keepout
				(tracks allowed)
				(vias not_allowed)
				(pads allowed)
				(copperpour not_allowed)
				(footprints allowed)
			)
			(placement
				(enabled no)
				(sheetname "")
			)
			(fill
				(thermal_gap 0.5)
				(thermal_bridge_width 0.5)
				(island_removal_mode 0)
			)
			(polygon
				(pts
					(xy 140.8938 -104.8258) (xy 140.8938 -104.2162) (xy 141.0462 -104.2162) (xy 141.0462 -104.8258)
				)
			)
		)
	)
)
